(kicad_pcb
	(version 20241229)
	(generator "pcbnew")
	(generator_version "9.0")
	(general
		(thickness 1.6642)
		(legacy_teardrops no)
	)
	(paper "A3")
	(title_block
		(title "PolarFire SoM")
		(date "2025-07-22")
		(rev "1.1.4")
		(company "Antmicro Ltd")
		(comment 1 "www.antmicro.com")
		(comment 9 "footprints 398-402 of 470")
	)
	(layers
		(0 "F.Cu" mixed)
		(4 "In1.Cu" power)
		(6 "In2.Cu" signal)
		(8 "In3.Cu" power)
		(10 "In4.Cu" signal)
		(12 "In5.Cu" power)
		(14 "In6.Cu" power)
		(16 "In7.Cu" signal)
		(18 "In8.Cu" power)
		(20 "In9.Cu" signal)
		(22 "In10.Cu" power)
		(24 "In11.Cu" signal)
		(26 "In12.Cu" signal)
		(2 "B.Cu" mixed)
		(9 "F.Adhes" user "F.Adhesive")
		(11 "B.Adhes" user "B.Adhesive")
		(13 "F.Paste" user)
		(15 "B.Paste" user)
		(5 "F.SilkS" user "F.Silkscreen")
		(7 "B.SilkS" user "B.Silkscreen")
		(1 "F.Mask" user)
		(3 "B.Mask" user)
		(17 "Dwgs.User" user "User.Drawings")
		(19 "Cmts.User" user "User.Comments")
		(21 "Eco1.User" user "User.Eco1")
		(23 "Eco2.User" user "User.Eco2")
		(25 "Edge.Cuts" user)
		(27 "Margin" user)
		(31 "F.CrtYd" user "F.Courtyard")
		(29 "B.CrtYd" user "B.Courtyard")
		(35 "F.Fab" user)
		(33 "B.Fab" user)
	)
	(footprint "antmicro-footprints:R_0402_1005Metric"
		(layer "B.Cu")
		(at 221.35 133.755 -90)
		(descr "Resistor SMD 0402")
		(tags "resistor SMD 0402")
		(property "Reference" "R2"
			(at 0.27 0.525 90)
			(layer "B.SilkS")
			(effects
				(font
					(size 0.7 0.7)
					(thickness 0.15)
				)
				(justify left bottom mirror)
			)
		)
		(property "Value" "R_30k9_0402"
			(at -1.011843 -1.772047 90)
			(layer "B.Fab")
			(hide yes)
			(effects
				(font
					(size 0.7 0.7)
					(thickness 0.15)
				)
				(justify left bottom mirror)
			)
		)
		(property "Datasheet" "https://www.bourns.com/docs/product-datasheets/cr.pdf"
			(at 0 0 270)
			(layer "F.Fab")
			(hide yes)
			(effects
				(font
					(size 1.27 1.27)
					(thickness 0.15)
				)
			)
		)
		(property "Description" "SMD Chip Resistor"
			(at 0 0 270)
			(layer "F.Fab")
			(hide yes)
			(effects
				(font
					(size 1.27 1.27)
					(thickness 0.15)
				)
			)
		)
		(property "Author" "Antmicro"
			(at 87.595 355.105 0)
			(layer "B.Fab")
			(hide yes)
			(effects
				(font
					(size 1 1)
					(thickness 0.15)
				)
				(justify mirror)
			)
		)
		(property "License" "Apache-2.0"
			(at 87.595 355.105 0)
			(layer "B.Fab")
			(hide yes)
			(effects
				(font
					(size 1 1)
					(thickness 0.15)
				)
				(justify mirror)
			)
		)
		(property "MPN" "CR0402-FX-3092GLF"
			(at 87.595 355.105 0)
			(layer "B.Fab")
			(hide yes)
			(effects
				(font
					(size 1 1)
					(thickness 0.15)
				)
				(justify mirror)
			)
		)
		(property "Manufacturer" "Bourns"
			(at 87.595 355.105 0)
			(layer "B.Fab")
			(hide yes)
			(effects
				(font
					(size 1 1)
					(thickness 0.15)
				)
				(justify mirror)
			)
		)
		(property "Public" ""
			(at 87.595 355.105 0)
			(layer "B.Fab")
			(hide yes)
			(effects
				(font
					(size 1 1)
					(thickness 0.15)
				)
				(justify mirror)
			)
		)
		(property "Tolerance" "1%"
			(at 87.595 355.105 0)
			(layer "B.Fab")
			(hide yes)
			(effects
				(font
					(size 1 1)
					(thickness 0.15)
				)
				(justify mirror)
			)
		)
		(property "Val" "30k9"
			(at 87.595 355.105 0)
			(layer "B.Fab")
			(hide yes)
			(effects
				(font
					(size 1 1)
					(thickness 0.15)
				)
				(justify mirror)
			)
		)
		(sheetname "/Supply/")
		(sheetfile "supply.kicad_sch")
		(attr smd)
		(fp_rect
			(start -0.925 0.47)
			(end 0.925 -0.47)
			(stroke
				(width 0.05)
				(type default)
			)
			(fill no)
			(layer "B.CrtYd")
		)
		(fp_rect
			(start -0.5 0.25)
			(end 0.5 -0.25)
			(stroke
				(width 0.15)
				(type solid)
			)
			(fill no)
			(layer "B.Fab")
		)
		(fp_text user "${REFERENCE}"
			(at -0.95 -3.168 90)
			(layer "B.Fab")
			(effects
				(font
					(size 0.7 0.7)
					(thickness 0.15)
				)
				(justify left bottom mirror)
			)
		)
		(fp_text user "License: Apache-2.0"
			(at -0.95 -5.169 90)
			(layer "B.Fab")
			(effects
				(font
					(size 0.7 0.7)
					(thickness 0.15)
				)
				(justify left bottom mirror)
			)
		)
		(fp_text user "Author: Antmicro"
			(at -0.95 -4.169 90)
			(layer "B.Fab")
			(effects
				(font
					(size 0.7 0.7)
					(thickness 0.15)
				)
				(justify left bottom mirror)
			)
		)
		(pad "1" smd roundrect
			(at -0.48 0 270)
			(size 0.59 0.64)
			(layers "B.Cu" "B.Mask" "B.Paste")
			(roundrect_rratio 0.25)
			(net 186 "/Supply/PR")
			(pintype "passive")
		)
		(pad "2" smd roundrect
			(at 0.48 0 270)
			(size 0.59 0.64)
			(layers "B.Cu" "B.Mask" "B.Paste")
			(roundrect_rratio 0.25)
			(net 333 "GPIO_VREF")
			(pintype "passive")
		)
	)
	(footprint "antmicro-footprints:R_0402_1005Metric"
		(layer "B.Cu")
		(at 208.25 135.35 180)
		(descr "Resistor SMD 0402")
		(tags "resistor SMD 0402")
		(property "Reference" "R41"
			(at 0.85 -0.4 0)
			(layer "B.SilkS")
			(effects
				(font
					(size 0.7 0.7)
					(thickness 0.15)
				)
				(justify left bottom mirror)
			)
		)
		(property "Value" "R_4k7_0402"
			(at -1.011843 -1.772047 0)
			(layer "B.Fab")
			(hide yes)
			(effects
				(font
					(size 0.7 0.7)
					(thickness 0.15)
				)
				(justify left bottom mirror)
			)
		)
		(property "Datasheet" "https://www.bourns.com/docs/product-datasheets/cr.pdf"
			(at 0 0 180)
			(layer "F.Fab")
			(hide yes)
			(effects
				(font
					(size 1.27 1.27)
					(thickness 0.15)
				)
			)
		)
		(property "Description" "SMD Chip Resistor, 4.7 kohm, ± 1%, 62.5 mW, 0402 [1005 Metric], Thick Film, General Purpose"
			(at 0 0 180)
			(layer "F.Fab")
			(hide yes)
			(effects
				(font
					(size 1.27 1.27)
					(thickness 0.15)
				)
			)
		)
		(property "Author" "Antmicro"
			(at 416.5 270.7 0)
			(layer "B.Fab")
			(hide yes)
			(effects
				(font
					(size 1 1)
					(thickness 0.15)
				)
				(justify mirror)
			)
		)
		(property "License" "Apache-2.0"
			(at 416.5 270.7 0)
			(layer "B.Fab")
			(hide yes)
			(effects
				(font
					(size 1 1)
					(thickness 0.15)
				)
				(justify mirror)
			)
		)
		(property "MPN" "CR0402-FX-4701GLF"
			(at 416.5 270.7 0)
			(layer "B.Fab")
			(hide yes)
			(effects
				(font
					(size 1 1)
					(thickness 0.15)
				)
				(justify mirror)
			)
		)
		(property "Manufacturer" "Bourns"
			(at 416.5 270.7 0)
			(layer "B.Fab")
			(hide yes)
			(effects
				(font
					(size 1 1)
					(thickness 0.15)
				)
				(justify mirror)
			)
		)
		(property "Public" ""
			(at 416.5 270.7 0)
			(layer "B.Fab")
			(hide yes)
			(effects
				(font
					(size 1 1)
					(thickness 0.15)
				)
				(justify mirror)
			)
		)
		(property "Tolerance" "1%"
			(at 416.5 270.7 0)
			(layer "B.Fab")
			(hide yes)
			(effects
				(font
					(size 1 1)
					(thickness 0.15)
				)
				(justify mirror)
			)
		)
		(property "Val" "4k7"
			(at 416.5 270.7 0)
			(layer "B.Fab")
			(hide yes)
			(effects
				(font
					(size 1 1)
					(thickness 0.15)
				)
				(justify mirror)
			)
		)
		(sheetname "/FPGA Config/")
		(sheetfile "fpga-config.kicad_sch")
		(attr smd)
		(fp_rect
			(start -0.925 0.47)
			(end 0.925 -0.47)
			(stroke
				(width 0.05)
				(type default)
			)
			(fill no)
			(layer "B.CrtYd")
		)
		(fp_rect
			(start -0.5 0.25)
			(end 0.5 -0.25)
			(stroke
				(width 0.15)
				(type solid)
			)
			(fill no)
			(layer "B.Fab")
		)
		(fp_text user "${REFERENCE}"
			(at -0.95 -3.168 0)
			(layer "B.Fab")
			(effects
				(font
					(size 0.7 0.7)
					(thickness 0.15)
				)
				(justify left bottom mirror)
			)
		)
		(fp_text user "License: Apache-2.0"
			(at -0.95 -5.169 0)
			(layer "B.Fab")
			(effects
				(font
					(size 0.7 0.7)
					(thickness 0.15)
				)
				(justify left bottom mirror)
			)
		)
		(fp_text user "Author: Antmicro"
			(at -0.95 -4.169 0)
			(layer "B.Fab")
			(effects
				(font
					(size 0.7 0.7)
					(thickness 0.15)
				)
				(justify left bottom mirror)
			)
		)
		(pad "1" smd roundrect
			(at -0.48 0 180)
			(size 0.59 0.64)
			(layers "B.Cu" "B.Mask" "B.Paste")
			(roundrect_rratio 0.25)
			(net 50 "+3V3")
			(pintype "passive")
		)
		(pad "2" smd roundrect
			(at 0.48 0 180)
			(size 0.59 0.64)
			(layers "B.Cu" "B.Mask" "B.Paste")
			(roundrect_rratio 0.25)
			(net 256 "Net-(U1D-SPI_EN)")
			(pintype "passive")
		)
	)
	(footprint "antmicro-footprints:C_0603_1608Metric"
		(layer "B.Cu")
		(at 190.1 141.101)
		(descr "Capacitor SMD 0603")
		(tags "capacitor 0603")
		(property "Reference" "C66"
			(at -1.503 -0.701 0)
			(layer "B.SilkS")
			(effects
				(font
					(size 0.7 0.7)
					(thickness 0.15)
				)
				(justify right bottom mirror)
			)
		)
		(property "Value" "C_47u_0603"
			(at -1.42757 -1.770288 0)
			(layer "B.Fab")
			(hide yes)
			(effects
				(font
					(size 0.7 0.7)
					(thickness 0.15)
				)
				(justify right bottom mirror)
			)
		)
		(property "Datasheet" "https://www.murata.com/products/productdetail?partno=GRM188R60J476ME15%23"
			(at 0 0 0)
			(layer "F.Fab")
			(hide yes)
			(effects
				(font
					(size 1.27 1.27)
					(thickness 0.15)
				)
			)
		)
		(property "Description" "SMD Multilayer Ceramic Capacitor, 47 µF, 6.3 V, 0603 [1608 Metric], ± 20%, X5R, GRM Series"
			(at 0 0 0)
			(layer "F.Fab")
			(hide yes)
			(effects
				(font
					(size 1.27 1.27)
					(thickness 0.15)
				)
			)
		)
		(property "Author" "Antmicro"
			(at 0 0 0)
			(layer "B.Fab")
			(hide yes)
			(effects
				(font
					(size 1 1)
					(thickness 0.15)
				)
				(justify mirror)
			)
		)
		(property "Capacitance" "47u"
			(at 0 0 0)
			(layer "B.Fab")
			(hide yes)
			(effects
				(font
					(size 1 1)
					(thickness 0.15)
				)
				(justify mirror)
			)
		)
		(property "Dielectric" "X7R"
			(at 0 0 0)
			(layer "B.Fab")
			(hide yes)
			(effects
				(font
					(size 1 1)
					(thickness 0.15)
				)
				(justify mirror)
			)
		)
		(property "License" "Apache-2.0"
			(at 0 0 0)
			(layer "B.Fab")
			(hide yes)
			(effects
				(font
					(size 1 1)
					(thickness 0.15)
				)
				(justify mirror)
			)
		)
		(property "MPN" "GRM188R60J476ME15D"
			(at 0 0 0)
			(layer "B.Fab")
			(hide yes)
			(effects
				(font
					(size 1 1)
					(thickness 0.15)
				)
				(justify mirror)
			)
		)
		(property "Manufacturer" "Murata"
			(at 0 0 0)
			(layer "B.Fab")
			(hide yes)
			(effects
				(font
					(size 1 1)
					(thickness 0.15)
				)
				(justify mirror)
			)
		)
		(property "Public" ""
			(at 0 0 0)
			(layer "B.Fab")
			(hide yes)
			(effects
				(font
					(size 1 1)
					(thickness 0.15)
				)
				(justify mirror)
			)
		)
		(property "Val" "47u"
			(at 0 0 0)
			(layer "B.Fab")
			(hide yes)
			(effects
				(font
					(size 1 1)
					(thickness 0.15)
				)
				(justify mirror)
			)
		)
		(property "Voltage" "50V"
			(at 0 0 0)
			(layer "B.Fab")
			(hide yes)
			(effects
				(font
					(size 1 1)
					(thickness 0.15)
				)
				(justify mirror)
			)
		)
		(sheetname "/FPGA Supply/")
		(sheetfile "fpga-supply.kicad_sch")
		(attr smd)
		(fp_line
			(start -0.15 -0.4)
			(end 0.15 -0.4)
			(stroke
				(width 0.15)
				(type solid)
			)
			(layer "B.SilkS")
		)
		(fp_line
			(start -0.15 0.4)
			(end 0.15 0.4)
			(stroke
				(width 0.15)
				(type solid)
			)
			(layer "B.SilkS")
		)
		(fp_rect
			(start -1.25 0.65)
			(end 1.25 -0.65)
			(stroke
				(width 0.05)
				(type solid)
			)
			(fill no)
			(layer "B.CrtYd")
		)
		(fp_rect
			(start -0.8 0.4)
			(end 0.8 -0.4)
			(stroke
				(width 0.15)
				(type solid)
			)
			(fill no)
			(layer "B.Fab")
		)
		(fp_text user "${REFERENCE}"
			(at -1.682 -3.895 180)
			(layer "B.Fab")
			(effects
				(font
					(size 0.7 0.7)
					(thickness 0.15)
				)
				(justify left bottom mirror)
			)
		)
		(fp_text user "Author: Antmicro"
			(at -1.682 -4.894 180)
			(layer "B.Fab")
			(effects
				(font
					(size 0.7 0.7)
					(thickness 0.15)
				)
				(justify left bottom mirror)
			)
		)
		(fp_text user "License: Apache-2.0"
			(at -1.682 -5.895 180)
			(layer "B.Fab")
			(effects
				(font
					(size 0.7 0.7)
					(thickness 0.15)
				)
				(justify left bottom mirror)
			)
		)
		(pad "1" smd roundrect
			(at -0.7 0)
			(size 0.8 1)
			(layers "B.Cu" "B.Mask" "B.Paste")
			(roundrect_rratio 0.2)
			(net 417 "GND")
			(pintype "passive")
		)
		(pad "2" smd roundrect
			(at 0.7 0)
			(size 0.8 1)
			(layers "B.Cu" "B.Mask" "B.Paste")
			(roundrect_rratio 0.2)
			(net 48 "+1V8")
			(pintype "passive")
		)
	)
	(footprint "antmicro-footprints:R_0402_1005Metric"
		(layer "B.Cu")
		(at 185.188498 148.183898 -90)
		(descr "Resistor SMD 0402")
		(tags "resistor SMD 0402")
		(property "Reference" "R78"
			(at -1.083898 0.488498 90)
			(layer "B.SilkS")
			(effects
				(font
					(size 0.7 0.7)
					(thickness 0.15)
				)
				(justify left bottom mirror)
			)
		)
		(property "Value" "R_0R_0402"
			(at -1.011843 -1.772047 90)
			(layer "B.Fab")
			(hide yes)
			(effects
				(font
					(size 0.7 0.7)
					(thickness 0.15)
				)
				(justify left bottom mirror)
			)
		)
		(property "Datasheet" "https://industrial.panasonic.com/cdbs/www-data/pdf/RDA0000/AOA0000C301.pdf"
			(at 0 0 270)
			(layer "F.Fab")
			(hide yes)
			(effects
				(font
					(size 1.27 1.27)
					(thickness 0.15)
				)
			)
		)
		(property "Description" "SMD Chip Resistor, Jumper, 0 ohm, 100 mW, 0402 [1005 Metric], Thick Film, General Purpose"
			(at 0 0 270)
			(layer "F.Fab")
			(hide yes)
			(effects
				(font
					(size 1.27 1.27)
					(thickness 0.15)
				)
			)
		)
		(property "Author" "Antmicro"
			(at 37.0046 333.372396 0)
			(layer "B.Fab")
			(hide yes)
			(effects
				(font
					(size 1 1)
					(thickness 0.15)
				)
				(justify mirror)
			)
		)
		(property "Current" "1A"
			(at 37.0046 333.372396 0)
			(layer "B.Fab")
			(hide yes)
			(effects
				(font
					(size 1 1)
					(thickness 0.15)
				)
				(justify mirror)
			)
		)
		(property "License" "Apache-2.0"
			(at 37.0046 333.372396 0)
			(layer "B.Fab")
			(hide yes)
			(effects
				(font
					(size 1 1)
					(thickness 0.15)
				)
				(justify mirror)
			)
		)
		(property "MPN" "ERJ2GE0R00X"
			(at 37.0046 333.372396 0)
			(layer "B.Fab")
			(hide yes)
			(effects
				(font
					(size 1 1)
					(thickness 0.15)
				)
				(justify mirror)
			)
		)
		(property "Manufacturer" "Panasonic"
			(at 37.0046 333.372396 0)
			(layer "B.Fab")
			(hide yes)
			(effects
				(font
					(size 1 1)
					(thickness 0.15)
				)
				(justify mirror)
			)
		)
		(property "Public" ""
			(at 37.0046 333.372396 0)
			(layer "B.Fab")
			(hide yes)
			(effects
				(font
					(size 1 1)
					(thickness 0.15)
				)
				(justify mirror)
			)
		)
		(property "Tolerance" "~"
			(at 37.0046 333.372396 0)
			(layer "B.Fab")
			(hide yes)
			(effects
				(font
					(size 1 1)
					(thickness 0.15)
				)
				(justify mirror)
			)
		)
		(property "Val" "0R"
			(at 37.0046 333.372396 0)
			(layer "B.Fab")
			(hide yes)
			(effects
				(font
					(size 1 1)
					(thickness 0.15)
				)
				(justify mirror)
			)
		)
		(sheetname "/Supply/")
		(sheetfile "supply.kicad_sch")
		(attr smd)
		(fp_rect
			(start -0.925 0.47)
			(end 0.925 -0.47)
			(stroke
				(width 0.05)
				(type default)
			)
			(fill no)
			(layer "B.CrtYd")
		)
		(fp_rect
			(start -0.5 0.25)
			(end 0.5 -0.25)
			(stroke
				(width 0.15)
				(type solid)
			)
			(fill no)
			(layer "B.Fab")
		)
		(fp_text user "Author: Antmicro"
			(at -0.95 -4.169 90)
			(layer "B.Fab")
			(effects
				(font
					(size 0.7 0.7)
					(thickness 0.15)
				)
				(justify left bottom mirror)
			)
		)
		(fp_text user "${REFERENCE}"
			(at -0.95 -3.168 90)
			(layer "B.Fab")
			(effects
				(font
					(size 0.7 0.7)
					(thickness 0.15)
				)
				(justify left bottom mirror)
			)
		)
		(fp_text user "License: Apache-2.0"
			(at -0.95 -5.169 90)
			(layer "B.Fab")
			(effects
				(font
					(size 0.7 0.7)
					(thickness 0.15)
				)
				(justify left bottom mirror)
			)
		)
		(pad "1" smd roundrect
			(at -0.48 0 270)
			(size 0.59 0.64)
			(layers "B.Cu" "B.Mask" "B.Paste")
			(roundrect_rratio 0.25)
			(net 633 "Net-(U7-OUT4)")
			(pintype "passive")
		)
		(pad "2" smd roundrect
			(at 0.48 0 270)
			(size 0.59 0.64)
			(layers "B.Cu" "B.Mask" "B.Paste")
			(roundrect_rratio 0.25)
			(net 103 "2V5_CL")
			(pintype "passive")
		)
	)
	(footprint "antmicro-footprints:C_0402_1005Metric"
		(layer "B.Cu")
		(at 210.5516 122.4066)
		(descr "Capacitor SMD 0402")
		(tags "capacitor SMD 0402")
		(property "Reference" "C256"
			(at -3.6016 2.6184 0)
			(layer "B.SilkS")
			(effects
				(font
					(size 0.7 0.7)
					(thickness 0.15)
				)
				(justify right bottom mirror)
			)
		)
		(property "Value" "C_100n_0402"
			(at -1.022927 -2.155213 0)
			(layer "B.Fab")
			(hide yes)
			(effects
				(font
					(size 0.7 0.7)
					(thickness 0.15)
				)
				(justify right bottom mirror)
			)
		)
		(property "Datasheet" "https://www.murata.com/products/productdetail?partno=GRM155R61H104KE14%23"
			(at 0 0 0)
			(layer "F.Fab")
			(hide yes)
			(effects
				(font
					(size 1.27 1.27)
					(thickness 0.15)
				)
			)
		)
		(property "Description" "SMD Multilayer Ceramic Capacitor, 0.1 µF, 50 V, 0402 [1005 Metric], ± 10%, X5R, GRM Series"
			(at 0 0 0)
			(layer "F.Fab")
			(hide yes)
			(effects
				(font
					(size 1.27 1.27)
					(thickness 0.15)
				)
			)
		)
		(property "Author" "Antmicro"
			(at 0 0 0)
			(layer "B.Fab")
			(hide yes)
			(effects
				(font
					(size 1 1)
					(thickness 0.15)
				)
				(justify mirror)
			)
		)
		(property "DNP" "DNP"
			(at 0 0 0)
			(layer "B.Fab")
			(hide yes)
			(effects
				(font
					(size 1 1)
					(thickness 0.15)
				)
				(justify mirror)
			)
		)
		(property "Dielectric" "X5R"
			(at 0 0 0)
			(layer "B.Fab")
			(hide yes)
			(effects
				(font
					(size 1 1)
					(thickness 0.15)
				)
				(justify mirror)
			)
		)
		(property "License" "Apache-2.0"
			(at 0 0 0)
			(layer "B.Fab")
			(hide yes)
			(effects
				(font
					(size 1 1)
					(thickness 0.15)
				)
				(justify mirror)
			)
		)
		(property "MPN" "GRM155R61H104KE14D"
			(at 0 0 0)
			(layer "B.Fab")
			(hide yes)
			(effects
				(font
					(size 1 1)
					(thickness 0.15)
				)
				(justify mirror)
			)
		)
		(property "Manufacturer" "Murata"
			(at 0 0 0)
			(layer "B.Fab")
			(hide yes)
			(effects
				(font
					(size 1 1)
					(thickness 0.15)
				)
				(justify mirror)
			)
		)
		(property "Public" ""
			(at 0 0 0)
			(layer "B.Fab")
			(hide yes)
			(effects
				(font
					(size 1 1)
					(thickness 0.15)
				)
				(justify mirror)
			)
		)
		(property "Val" "100n"
			(at 0 0 0)
			(layer "B.Fab")
			(hide yes)
			(effects
				(font
					(size 1 1)
					(thickness 0.15)
				)
				(justify mirror)
			)
		)
		(property "Voltage" "50V"
			(at 0 0 0)
			(layer "B.Fab")
			(hide yes)
			(effects
				(font
					(size 1 1)
					(thickness 0.15)
				)
				(justify mirror)
			)
		)
		(sheetname "/Ethernet/")
		(sheetfile "ethernet.kicad_sch")
		(attr smd dnp)
		(fp_rect
			(start -0.925 0.47)
			(end 0.925 -0.47)
			(stroke
				(width 0.05)
				(type default)
			)
			(fill no)
			(layer "B.CrtYd")
		)
		(fp_line
			(start -0.494 -0.248)
			(end -0.494 0.25)
			(stroke
				(width 0.15)
				(type solid)
			)
			(layer "B.Fab")
		)
		(fp_line
			(start -0.494 0.25)
			(end 0.504 0.25)
			(stroke
				(width 0.15)
				(type solid)
			)
			(layer "B.Fab")
		)
		(fp_line
			(start 0.504 -0.248)
			(end -0.494 -0.248)
			(stroke
				(width 0.15)
				(type solid)
			)
			(layer "B.Fab")
		)
		(fp_line
			(start 0.504 0.25)
			(end 0.504 -0.248)
			(stroke
				(width 0.15)
				(type solid)
			)
			(layer "B.Fab")
		)
		(fp_text user "Author: Antmicro"
			(at -0.939 -3.399 180)
			(layer "B.Fab")
			(effects
				(font
					(size 0.7 0.7)
					(thickness 0.15)
				)
				(justify left bottom mirror)
			)
		)
		(fp_text user "License: Apache-2.0"
			(at -0.939 -5.799 180)
			(layer "B.Fab")
			(effects
				(font
					(size 0.7 0.7)
					(thickness 0.15)
				)
				(justify left bottom mirror)
			)
		)
		(fp_text user "${REFERENCE}"
			(at -0.939 -4.599 180)
			(layer "B.Fab")
			(effects
				(font
					(size 0.7 0.7)
					(thickness 0.15)
				)
				(justify left bottom mirror)
			)
		)
		(pad "1" smd roundrect
			(at -0.48 0)
			(size 0.59 0.64)
			(layers "B.Cu" "B.Mask" "B.Paste")
			(roundrect_rratio 0.25)
			(net 9 "MSS_REFCLK_N")
			(pintype "passive")
		)
		(pad "2" smd roundrect
			(at 0.48 0)
			(size 0.59 0.64)
			(layers "B.Cu" "B.Mask" "B.Paste")
			(roundrect_rratio 0.25)
			(net 165 "/Ethernet/SGMII_CO_N")
			(pintype "passive")
		)
	)
)
